#ISCELL
  mstr_misc dns *
  *
#ISCELL
  pure_quanta quanta_title_block_c *
  *
#ISCELL
  standard offpage *
  page229_i1
#ISCELL
  logical_power universal_gnd *
  page229_i10
#CELL
  pure_quanta q_res *
  page229_i11
#CELL
  pure_quanta q_res *
  page229_i12
#ISCELL
  logical_power gnd *
  page229_i13
#CELL
  pure_quanta q_res *
  page229_i14
#ISCELL
  standard offpage *
  page229_i15
#ISCELL
  logical_power universal_power *
  page229_i16
#CELL
  pure_quanta q_res *
  page229_i17
#CELL
  pure_quanta q_res *
  page229_i18
#ISCELL
  logical_power universal_power *
  page229_i19
#CELL
  pure_quanta q_res *
  page229_i2
#CELL
  pure_quanta q_res *
  page229_i20
#CELL
  pure_quanta mosfet_nch_dual *
  page229_i21
#ISCELL
  logical_power gnd *
  page229_i22
#ISCELL
  logical_power gnd *
  page229_i23
#CELL
  pure_quanta q_res *
  page229_i24
#ISCELL
  logical_power universal_power *
  page229_i25
#CELL
  pure_quanta mosfet_nch_dual *
  page229_i26
#CELL
  pure_quanta q_res *
  page229_i27
#ISCELL
  logical_power gnd *
  page229_i28
#CELL
  pure_quanta diode_tvs *
  page229_i29
#CELL
  pure_quanta q_res *
  page229_i3
#ISCELL
  logical_power universal_power *
  page229_i30
#CELL
  pure_quanta q_cap *
  page229_i31
#ISCELL
  logical_power gnd *
  page229_i32
#CELL
  pure_quanta q_cap *
  page229_i33
#CELL
  pure_quanta q_res *
  page229_i34
#ISCELL
  logical_power gnd *
  page229_i35
#ISCELL
  logical_power gnd *
  page229_i36
#CELL
  pure_quanta q_cap *
  page229_i37
#ISCELL
  logical_power universal_power *
  page229_i38
#CELL
  pure_quanta q_res *
  page229_i39
#ISCELL
  logical_power gnd *
  page229_i4
#CELL
  pure_quanta q_cap *
  page229_i42
#ISCELL
  logical_power gnd *
  page229_i43
#CELL
  pure_quanta q_res *
  page229_i44
#ISCELL
  logical_power gnd *
  page229_i45
#ISCELL
  standard offpage *
  page229_i46
#ISCELL
  standard offpage *
  page229_i47
#CELL
  pure_quanta q_res *
  page229_i48
#ISCELL
  logical_power vccaux15 *
  page229_i49
#ISCELL
  logical_power gnd *
  page229_i5
#CELL
  pure_quanta q_res *
  page229_i50
#CELL
  pure_quanta q_res *
  page229_i51
#CELL
  pure_quanta q_res *
  page229_i52
#CELL
  pure_quanta q_cap *
  page229_i53
#CELL
  pure_quanta q_res *
  page229_i54
#ISCELL
  logical_power universal_power *
  page229_i55
#ISCELL
  logical_power gnd *
  page229_i56
#CELL
  pure_quanta q_cap *
  page229_i57
#ISCELL
  logical_power universal_power *
  page229_i58
#ISCELL
  standard offpage *
  page229_i59
#ISCELL
  logical_power gnd *
  page229_i6
#ISCELL
  logical_power gnd *
  page229_i60
#CELL
  pure_quanta q_res *
  page229_i61
#ISCELL
  logical_power gnd *
  page229_i62
#CELL
  pure_quanta q_res *
  page229_i63
#CELL
  pure_quanta q_res *
  page229_i64
#ISCELL
  logical_power gnd *
  page229_i65
#CELL
  pure_quanta q_cap *
  page229_i66
#CELL
  pure_quanta q_res *
  page229_i67
#CELL
  pure_quanta q_cap *
  page229_i68
#CELL
  pure_quanta max15090bewit *
  page229_i69
#CELL
  pure_quanta q_cap *
  page229_i7
#CELL
  pure_quanta q_res *
  page229_i70
#ISCELL
  logical_power gnd *
  page229_i71
#CELL
  pure_quanta q_res *
  page229_i72
#CELL
  pure_quanta q_cap *
  page229_i73
#CELL
  pure_quanta q_res *
  page229_i74
#CELL
  pure_quanta q_cap *
  page229_i75
#CELL
  pure_quanta q_res *
  page229_i76
#CELL
  pure_quanta q_res *
  page229_i77
#ISCELL
  logical_power gnd *
  page229_i78
#CELL
  pure_quanta q_res *
  page229_i79
#CELL
  pure_quanta q_cap *
  page229_i8
#ISCELL
  logical_power vccaux15 *
  page229_i80
#CELL
  pure_quanta q_res *
  page229_i81
#CELL
  pure_quanta schottky_ac *
  page229_i82
#CELL
  pure_quanta q_cap *
  page229_i83
#CELL
  pure_quanta q_cap *
  page229_i84
#ISCELL
  standard offpage *
  page229_i85
#ISCELL
  standard offpage *
  page229_i86
#ISCELL
  logical_power gnd *
  page229_i87
#CELL
  pure_quanta q_cap *
  page229_i88
#ISCELL
  logical_power universal_power *
  page229_i89
#CELL
  pure_quanta mosfet_nch_gds_esd_protected *
  page229_i9
#CELL
  pure_quanta rs31312r *
  page229_i90
#CELL
  pure_quanta q_res *
  page229_i91
#CELL
  pure_quanta q_res *
  page229_i92
#ISCELL
  logical_power vccaux15 *
  page229_i93
#ISCELL
  standard offpage *
  page229_i94
